(kicad_pcb
	(version 20260206)
	(generator "pcbnew")
	(generator_version "10.0")
	(general
		(thickness 1.6)
		(legacy_teardrops no)
	)
	(paper "A4")
	(title_block
		(title "Wiwynn_Tioga_Pass_MB.brd")
		(comment 1 "Tioga Pass / footprint 153 of 4770 (U25W4), pads 435-456 of 456")
	)
	(layers
		(0 "F.Cu" signal "TOP")
		(4 "In1.Cu" signal "L2GND")
		(6 "In2.Cu" signal "L3")
		(8 "In3.Cu" signal "L4GND")
		(10 "In4.Cu" signal "L5")
		(12 "In5.Cu" signal "L6GND")
		(14 "In6.Cu" signal "L7VCC")
		(16 "In7.Cu" signal "L8VCC")
		(18 "In8.Cu" signal "L9GND")
		(20 "In9.Cu" signal "L10")
		(22 "In10.Cu" signal "L11GND")
		(24 "In11.Cu" signal "L12")
		(26 "In12.Cu" signal "L13GND")
		(2 "B.Cu" signal "BOTTOM")
		(9 "F.Adhes" user "F.Adhesive")
		(11 "B.Adhes" user "B.Adhesive")
		(13 "F.Paste" user "Package Geometry/Pastemask Top")
		(15 "B.Paste" user "Package Geometry/Pastemask Bottom")
		(5 "F.SilkS" user "Ref Des/Silkscreen Top")
		(7 "B.SilkS" user "Ref Des/Silkscreen Bottom")
		(1 "F.Mask" user "Board Geometry/Soldermask Top")
		(3 "B.Mask" user "Board Geometry/Soldermask Bottom")
		(17 "Dwgs.User" user "User.Drawings")
		(19 "Cmts.User" user "User.Comments")
		(21 "Eco1.User" user "User.Eco1")
		(23 "Eco2.User" user "User.Eco2")
		(25 "Edge.Cuts" user "Board Geometry/Outline")
		(27 "Margin" user)
		(31 "F.CrtYd" user "Package Geometry/Place Bound Top")
		(29 "B.CrtYd" user "Package Geometry/Place Bound Bottom")
		(35 "F.Fab" user "Ref Des/Assembly Top")
		(33 "B.Fab" user "Ref Des/Assembly Bottom")
	)
	(footprint ""
		(layer "F.Cu")
		(at 415.490152 -34.934652 90)
		(property "Reference" "U25W4"
			(at 0 0 90)
			(layer "F.SilkS")
			(hide yes)
			(effects
				(font
					(size 1.27 1.27)
				)
			)
		)
		(property "Value" "*"
			(at -17.0307 -8.698992 90)
			(unlocked yes)
			(layer "F.Fab")
			(hide yes)
			(effects
				(font
					(size 1.27 1.016)
					(thickness 0.1524)
				)
			)
		)
		(property "Device Type" "AST2520A1-GP-GP_ASIC2-GB1-AST2A"
			(at -17.0307 -10.222992 90)
			(unlocked yes)
			(layer "F.Fab")
			(hide yes)
			(effects
				(font
					(size 1.27 1.016)
					(thickness 0.1524)
				)
			)
		)
		(duplicate_pad_numbers_are_jumpers no)
		(pad "Y1" smd circle
			(at -8.400034 6.800088 90)
			(size 0.4064 0.4064)
			(layers "F.Cu" "F.Mask" "F.Paste")
			(net "FM_CPU0_RC_ERROR_N")
		)
		(pad "Y2" smd circle
			(at -7.599934 6.800088 90)
			(size 0.4064 0.4064)
			(layers "F.Cu" "F.Mask" "F.Paste")
			(net "FM_OC_DETECT_EN_N")
		)
		(pad "Y3" smd circle
			(at -6.800088 6.800088 90)
			(size 0.4064 0.4064)
			(layers "F.Cu" "F.Mask" "F.Paste")
			(net "PUMP_PWM_OUT")
		)
		(pad "Y4" smd circle
			(at -5.999988 6.800088 90)
			(size 0.3556 0.3556)
			(layers "F.Cu" "F.Mask" "F.Paste")
			(net "PUMP_TACH1")
		)
		(pad "Y5" smd circle
			(at -5.199888 6.800088 90)
			(size 0.3556 0.3556)
			(layers "F.Cu" "F.Mask" "F.Paste")
			(net "BMC_PREQ_N")
		)
		(pad "Y6" smd circle
			(at -4.400042 6.800088 90)
			(size 0.3556 0.3556)
			(layers "F.Cu" "F.Mask" "F.Paste")
			(net "FM_BOARD_SKU_ID4")
		)
		(pad "Y7" smd circle
			(at -3.599942 6.800088 90)
			(size 0.3556 0.3556)
			(layers "F.Cu" "F.Mask" "F.Paste")
			(net "BMC_M_DQ10")
		)
		(pad "Y8" smd circle
			(at -2.800096 6.800088 90)
			(size 0.3556 0.3556)
			(layers "F.Cu" "F.Mask" "F.Paste")
			(net "BMC_M_DQ9")
		)
		(pad "Y9" smd circle
			(at -1.999996 6.800088 90)
			(size 0.3556 0.3556)
			(layers "F.Cu" "F.Mask" "F.Paste")
			(net "BMC_M_DQ5")
		)
		(pad "Y10" smd circle
			(at -1.199896 6.800088 90)
			(size 0.3556 0.3556)
			(layers "F.Cu" "F.Mask" "F.Paste")
			(net "BMC_M_DQ2")
		)
		(pad "Y11" smd circle
			(at -0.40005 6.800088 90)
			(size 0.3556 0.3556)
			(layers "F.Cu" "F.Mask" "F.Paste")
			(net "BMC_M_CKE")
		)
		(pad "Y12" smd circle
			(at 0.40005 6.800088 90)
			(size 0.3556 0.3556)
			(layers "F.Cu" "F.Mask" "F.Paste")
			(net "BMC_M_WE_N")
		)
		(pad "Y13" smd circle
			(at 1.199896 6.800088 90)
			(size 0.3556 0.3556)
			(layers "F.Cu" "F.Mask" "F.Paste")
			(net "BMC_M_BA1")
		)
		(pad "Y14" smd circle
			(at 1.999996 6.800088 90)
			(size 0.3556 0.3556)
			(layers "F.Cu" "F.Mask" "F.Paste")
			(net "BMC_M_A12")
		)
		(pad "Y15" smd circle
			(at 2.800096 6.800088 90)
			(size 0.3556 0.3556)
			(layers "F.Cu" "F.Mask" "F.Paste")
			(net "BMC_M_MACT_N")
		)
		(pad "Y16" smd circle
			(at 3.599942 6.800088 90)
			(size 0.3556 0.3556)
			(layers "F.Cu" "F.Mask" "F.Paste")
			(net "BMC_M_A9")
		)
		(pad "Y17" smd circle
			(at 4.400042 6.800088 90)
			(size 0.3556 0.3556)
			(layers "F.Cu" "F.Mask" "F.Paste")
			(net "VCC_PA_3V3")
		)
		(pad "Y18" smd circle
			(at 5.199888 6.800088 90)
			(size 0.3556 0.3556)
			(layers "F.Cu" "F.Mask" "F.Paste")
			(net "FM_BMC_HEARTBEAT_N")
		)
		(pad "Y19" smd circle
			(at 5.999988 6.800088 90)
			(size 0.3556 0.3556)
			(layers "F.Cu" "F.Mask" "F.Paste")
			(net "BMC_PRDY_N")
		)
		(pad "Y20" smd circle
			(at 6.800088 6.800088 90)
			(size 0.4064 0.4064)
			(layers "F.Cu" "F.Mask" "F.Paste")
			(net "FM_BMC_CPLD_GPO")
		)
		(pad "Y21" smd circle
			(at 7.599934 6.800088 90)
			(size 0.4064 0.4064)
			(layers "F.Cu" "F.Mask" "F.Paste")
			(net "FM_CPU1_SKTOCC_LVT3_N")
		)
		(pad "Y22" smd circle
			(at 8.400034 6.800088 90)
			(size 0.4064 0.4064)
			(layers "F.Cu" "F.Mask" "F.Paste")
			(net "FP_PWR_ID_LED_N")
		)
	)
)
